FILE_TYPE = CONNECTIVITY;
{Allegro Design Entry HDL 17.4-2019 S026 (4007227) 1/17/2022}
"PAGE_NUMBER" = 174;
0"NC";
1"GND\g";
2"GND\g";
3"GND\g";
4"GND\g";
5"GND\g";
6"SW_P12V_AUX_PVDDCR_SOC_P0_FLT\g";
7"GND\g";
8"SW_PVDDCR_SOC_P0_BOOT3";
9"SW_PVDDCR_SOC_P0_BOOT3_RC";
10"SW_PVDDCR_SOC_P0_PH3";
11"PVDDCR_SOC_P0_VOS3";
12"SW_PVDDCR_SOC_P0_SW3";
13"IND_SOC_P0_CPL3";
14"IND_SOC_P0_CPL0";
15"PVDDCR_SOC_P0_IMON3";
16"SW_PVDDCR_SOC_P0_SW3_RC";
17"NC_PVDDCR_SOC_P0_GL2_3";
18"NC_PVDDCR_SOC_P0_GL1_3";
19"PVDDCR_SOC_P0_LSET3";
20"NC_PVDDCR_SOC_P0_DNC3";
21"PVDDCR_SOC_P0_TEMP1";
22"PVDDCR_SOC_P0_PWM3";
23"PVDDCR_CPU0_P0_VCCS";
24"PVDDCR_SOC_P0_VCC3";
25"GND\g";
26"PVDDCR_SOC_P0\g";
27"GND\g";
28"GND\g";
29"PVDDCR_CPU0_P0_PVCC\g";
%"Q_RES"
"2","(-4375,3575)","0","pure_quanta","I10";
;
LOCATION"PR505"
$SEC"1"
CDS_SEC"1"
PACK_TYPE"0402LF"
TOLERANCE"1%"
MATERIAL"EMPTY"
WATTAGE"1/8W"
VALUE"1.5"
CDS_LIB"pure_quanta"
PART_NUMBER"CS-1504FB00";
"A"
$PN"1"16;
"B"
$PN"2"5;
%"Q_RES"
"1","(-3950,3275)","0","pure_quanta","I11";
;
LOCATION"PR367"
$SEC"1"
CDS_SEC"1"
WATTAGE"1/16W"
MATERIAL"CHIP"
TOLERANCE"5%"
VALUE"0"
PACK_TYPE"0402LF"
CDS_LIB"pure_quanta"
PART_NUMBER"CS00002JB13";
"B"
$PN"2"26;
"A"
$PN"1"11;
%"Q_CAP"
"1","(-4375,4050)","0","pure_quanta","I12";
;
LOCATION"PC188"
$SEC"1"
CDS_SEC"1"
MATERIAL"EMPTY"
VOLTAGE"50V"
VALUE"560PF"
TOLERANCE"10%"
PACK_TYPE"C0402"
CDS_LIB"pure_quanta"
PART_NUMBER"CH1566K1B09";
"B"
$PN"2"16;
"A"
$PN"1"12;
%"UNIVERSAL_GND"
"1","(-7225,4375)","0","pure_quanta_power","I13";
;
CDS_LIB"pure_quanta_power"
HDL_POWER"GND";
"A"1;
%"Q_CAP"
"1","(-7225,4575)","0","pure_quanta","I14";
;
LOCATION"PC606"
$SEC"1"
CDS_SEC"1"
MATERIAL"X6S"
PACK_TYPE"C0402"
VOLTAGE"10V"
VALUE"2.2UF"
TOLERANCE"10%"
CDS_LIB"pure_quanta"
PART_NUMBER"CH5222KEB01";
"B"
$PN"2"1;
"A"
$PN"1"24;
%"Q_RES"
"2","(-7225,5050)","0","pure_quanta","I15";
;
LOCATION"PR364"
$SEC"1"
CDS_SEC"1"
WATTAGE"1/16W"
MATERIAL"CHIP"
TOLERANCE"1%"
VALUE"2.2"
PACK_TYPE"0402LF"
CDS_LIB"pure_quanta"
PART_NUMBER"CS-2202FB01";
"A"
$PN"1"29;
"B"
$PN"2"24;
%"VCC_CORE"
"1","(-7225,5450)","0","pure_quanta_power","I16";
;
HDL_POWER"PVDDCR_CPU0_P0_PVCC"
CDS_LIB"pure_quanta_power";
"A"29;
%"UNIVERSAL_GND"
"1","(-6875,4800)","0","pure_quanta_power","I18";
;
CDS_LIB"pure_quanta_power"
HDL_POWER"GND";
"A"2;
%"Q_CAP"
"1","(-6875,5050)","0","pure_quanta","I19";
;
LOCATION"PC607_SOP0_3"
$SEC"1"
CDS_SEC"1"
PACK_TYPE"C0402"
VOLTAGE"10V"
VALUE"2.2UF"
TOLERANCE"10%"
MATERIAL"X6S"
CDS_LIB"pure_quanta"
PART_NUMBER"CH5222KEB01";
"B"
$PN"2"2;
"A"
$PN"1"29;
%"Q_CAP"
"1","(-7550,3950)","0","pure_quanta","I2";
;
LOCATION"PC605_9"
$SEC"1"
CDS_SEC"1"
PACK_TYPE"0402"
VOLTAGE"25V"
VALUE"0.1UF"
TOLERANCE"10%"
MATERIAL"X7R"
CDS_LIB"pure_quanta"
PART_NUMBER"CH4104K1B00";
"B"
$PN"2"3;
"A"
$PN"1"23;
%"Q_RES"
"1","(-4425,4575)","0","pure_quanta","I20";
;
LOCATION"PR366"
$SEC"1"
CDS_SEC"1"
TOLERANCE"1%"
WATTAGE"1/16W"
PACK_TYPE"0402LF"
MATERIAL"CHIP"
VALUE"5.6"
CDS_LIB"pure_quanta"
PART_NUMBER"CS-5602FB01";
"B"
$PN"2"9;
"A"
$PN"1"8;
%"Q_CAP"
"1","(-4525,5100)","0","pure_quanta","I21";
;
LOCATION"PC608_3"
$SEC"1"
CDS_SEC"1"
MATERIAL"X6S"
VALUE"1UF"
VOLTAGE"25V"
TOLERANCE"10%"
PACK_TYPE"C0402"
CDS_LIB"pure_quanta"
PART_NUMBER"CH5104KEB02";
"B"
$PN"2"7;
"A"
$PN"1"6;
%"Q_CAP"
"1","(-4200,5100)","0","pure_quanta","I22";
;
LOCATION"PC610_3"
$SEC"1"
CDS_SEC"1"
PACK_TYPE"C0805"
MATERIAL"X6S"
TOLERANCE"20%"
VOLTAGE"16V"
VALUE"22UF"
CDS_LIB"pure_quanta"
PART_NUMBER"CH6223MEA01";
"B"
$PN"2"7;
"A"
$PN"1"6;
%"UNIVERSAL_GND"
"1","(-3975,3875)","0","pure_quanta_power","I23";
;
CDS_LIB"pure_quanta_power"
HDL_POWER"GND";
"A"28;
%"Q_INDUCTOR"
"1","(-3775,4000)","0","pure_quanta","I24";
;
LOCATION"PL62"
$SEC"1"
CDS_SEC"1"
PACK_TYPE"SMLF"
MATERIAL"IND"
VALUE"0.22UH/33A"
CDS_LIB"pure_quanta"
NEEDS_NO_SIZE"TRUE"
PART_NUMBER"CV+22Y0EZ00";
"1"
$PN"1"28;
"2"
$PN"2"14;
%"Q_INDUCTOR4P_14"
"1","(-2825,4100)","0","pure_quanta","I25";
;
LOCATION"PL66"
$SEC"1"
CDS_SEC"1"
MATERIAL"IND"
VALUE"150NH"
PART_TYPE"SMLF"
NEEDS_NO_SIZE"TRUE"
CDS_LIB"pure_quanta"
PART_NUMBER"CV+15^0TZ04";
"1"
$PN"1"12;
"4"
$PN"4"26;
"3"
$PN"3"13;
"2"
$PN"2"14;
%"Q_CAP"
"1","(-1650,4050)","0","pure_quanta","I27";
;
LOCATION"PC614_3"
$SEC"1"
CDS_SEC"1"
PACK_TYPE"C0805"
MATERIAL"X6S"
TOLERANCE"20%"
VALUE"22UF"
VOLTAGE"4V"
CDS_LIB"pure_quanta"
PART_NUMBER"CH622KMEA03";
"B"
$PN"2"27;
"A"
$PN"1"26;
%"UNIVERSAL_GND"
"1","(-1225,3700)","0","pure_quanta_power","I28";
;
CDS_LIB"pure_quanta_power"
HDL_POWER"GND";
"A"27;
%"Q_CAP"
"1","(-1225,4050)","0","pure_quanta","I29";
;
LOCATION"PC615_3"
$SEC"1"
CDS_SEC"1"
VALUE"22UF"
PACK_TYPE"C0805"
MATERIAL"X6S"
TOLERANCE"20%"
VOLTAGE"4V"
CDS_LIB"pure_quanta"
PART_NUMBER"CH622KMEA03";
"B"
$PN"2"27;
"A"
$PN"1"26;
%"UNIVERSAL_GND"
"1","(-7550,3675)","0","pure_quanta_power","I3";
;
CDS_LIB"pure_quanta_power"
HDL_POWER"GND";
"A"3;
%"Q_CAP"
"1","(-3600,4450)","0","pure_quanta","I30";
;
LOCATION"PC612"
$SEC"1"
CDS_SEC"1"
PACK_TYPE"0402"
VOLTAGE"16V"
VALUE"0.22UF"
TOLERANCE"10%"
MATERIAL"X7R"
CDS_LIB"pure_quanta"
PART_NUMBER"CH4223K1B00";
"B"
$PN"2"10;
"A"
$PN"1"9;
%"Q_CAP"
"1","(-3875,5100)","0","pure_quanta","I31";
;
LOCATION"PC611_3"
$SEC"1"
CDS_SEC"1"
MATERIAL"X6S"
TOLERANCE"20%"
VOLTAGE"16V"
VALUE"22UF"
PACK_TYPE"C0805"
CDS_LIB"pure_quanta"
PART_NUMBER"CH6223MEA01";
"B"
$PN"2"7;
"A"
$PN"1"6;
%"Q_CAP"
"1","(-3575,5100)","0","pure_quanta","I32";
;
LOCATION"PC613_3"
$SEC"1"
CDS_SEC"1"
TOLERANCE"20%"
VOLTAGE"16V"
MATERIAL"X6S"
PACK_TYPE"C0805"
VALUE"22UF"
CDS_LIB"pure_quanta"
PART_NUMBER"CH6223MEA01";
"B"
$PN"2"7;
"A"
$PN"1"6;
%"UNIVERSAL_GND"
"1","(-3225,4775)","0","pure_quanta_power","I33";
;
CDS_LIB"pure_quanta_power"
HDL_POWER"GND";
"A"7;
%"Q_CAP"
"1","(-3225,5100)","0","pure_quanta","I34";
;
LOCATION"PC612_3"
$SEC"1"
CDS_SEC"1"
TOLERANCE"20%"
VOLTAGE"16V"
VALUE"22UF"
MATERIAL"X6S"
PACK_TYPE"C0805"
CDS_LIB"pure_quanta"
PART_NUMBER"CH6223MEA01";
"B"
$PN"2"7;
"A"
$PN"1"6;
%"VCC_CORE"
"1","(-3225,5400)","0","pure_quanta_power","I35";
;
HDL_POWER"SW_P12V_AUX_PVDDCR_SOC_P0_FLT"
CDS_LIB"pure_quanta_power";
"A"6;
%"VCC_CORE"
"1","(-1225,4375)","0","pure_quanta_power","I36";
;
HDL_POWER"PVDDCR_SOC_P0"
CDS_LIB"pure_quanta_power";
"A"26;
%"Q_CAP"
"1","(-4925,5100)","0","pure_quanta","I37";
;
LOCATION"PC609_3"
$SEC"1"
CDS_SEC"1"
VALUE"0.1UF"
VOLTAGE"25V"
TOLERANCE"10%"
PACK_TYPE"0402"
MATERIAL"X7R"
CDS_LIB"pure_quanta"
PART_NUMBER"CH4104K1B00";
"B"
$PN"2"7;
"A"
$PN"1"6;
%"ISL99390FRZTR5935"
"1","(-5725,4225)","0","pure_quanta","I38";
;
LOCATION"PU51"
$SEC"1"
CDS_SEC"1"
PART_TYPE"SMLF"
MATERIAL"IC"
VALUE"ISL99390FRZ-TR5935"
CDS_LMAN_SYM_OUTLINE"-300,700,250,-650"
NEEDS_NO_SIZE"TRUE"
CDS_LIB"pure_quanta"
PART_NUMBER"AL099390004";
"PGND2"
$PN"7_9-20_24"25;
"GL2"
$PN"41"17;
"GL1"
$PN"6"18;
"DNC"
$PN"31"20;
"EN"
$PN"35"24;
"PGND3"
$PN"40"25;
"VOS"
$PN"1"11;
"VIN2"
$PN"30"6;
"PGND1"
$PN"5"25;
"SW"
$PN"10_19"12;
"LSET"
$PN"37"19;
"IOUT"
$PN"38"15;
"TOUT_FLT"
$PN"36"21;
"PVCC"
$PN"4"29;
"PHASE"
$PN"32"10;
"VIN1"
$PN"25_29"6;
"BOOT"
$PN"33"8;
"AGND"
$PN"2"25;
"VCC"
$PN"3"24;
"REFIN"
$PN"39"23;
"PWM"
$PN"34"22;
%"UNIVERSAL_GND"
"1","(-7225,3750)","0","pure_quanta_power","I4";
;
CDS_LIB"pure_quanta_power"
HDL_POWER"GND";
"A"4;
%"Q_RES"
"1","(-6900,3925)","0","pure_quanta","I7";
;
LOCATION"PR365"
$SEC"1"
CDS_SEC"1"
WATTAGE"1/16W"
MATERIAL"EMPTY"
VALUE"8.87K"
PACK_TYPE"0402LF"
TOLERANCE"1%"
CDS_LIB"pure_quanta"
PART_NUMBER"CS28872FB01";
"B"
$PN"2"19;
"A"
$PN"1"4;
%"UNIVERSAL_GND"
"1","(-5150,3500)","0","pure_quanta_power","I8";
;
CDS_LIB"pure_quanta_power"
HDL_POWER"GND";
"A"25;
%"UNIVERSAL_GND"
"1","(-4375,3350)","0","pure_quanta_power","I9";
;
CDS_LIB"pure_quanta_power"
HDL_POWER"GND";
"A"5;
END.
